(kicad_pcb
	(version 20260206)
	(generator "pcbnew")
	(generator_version "10.0")
	(general
		(thickness 1.6)
		(legacy_teardrops no)
	)
	(paper "A4")
	(title_block
		(title "baseboard — 13948-1b.1110WZS1818.brd")
		(comment 1 "Honey Badger (Wiwynn) / footprints 1783-1792 of 2523")
	)
	(layers
		(0 "F.Cu" signal "TOP")
		(4 "In1.Cu" signal "L2GND")
		(6 "In2.Cu" signal "L3")
		(8 "In3.Cu" signal "L4VCC")
		(10 "In4.Cu" signal "L5VCC")
		(12 "In5.Cu" signal "L6")
		(14 "In6.Cu" signal "L7GND")
		(2 "B.Cu" signal "BOTTOM")
		(9 "F.Adhes" user "F.Adhesive")
		(11 "B.Adhes" user "B.Adhesive")
		(13 "F.Paste" user "Package Geometry/Pastemask Top")
		(15 "B.Paste" user "Package Geometry/Pastemask Bottom")
		(5 "F.SilkS" user "Ref Des/Silkscreen Top")
		(7 "B.SilkS" user "Ref Des/Silkscreen Bottom")
		(1 "F.Mask" user "Board Geometry/Soldermask Top")
		(3 "B.Mask" user "Board Geometry/Soldermask Bottom")
		(17 "Dwgs.User" user "User.Drawings")
		(19 "Cmts.User" user "User.Comments")
		(21 "Eco1.User" user "User.Eco1")
		(23 "Eco2.User" user "User.Eco2")
		(25 "Edge.Cuts" user "Board Geometry/Outline")
		(27 "Margin" user)
		(31 "F.CrtYd" user "Package Geometry/Place Bound Top")
		(29 "B.CrtYd" user "Package Geometry/Place Bound Bottom")
		(35 "F.Fab" user "Ref Des/Assembly Top")
		(33 "B.Fab" user "Ref Des/Assembly Bottom")
	)
	(footprint ""
		(layer "B.Cu")
		(at 95.26016 -50.165)
		(property "Reference" "STP37"
			(at 0 0 0)
			(layer "B.SilkS")
			(hide yes)
			(effects
				(font
					(size 1.27 1.27)
				)
				(justify mirror)
			)
		)
		(property "Value" "TPAD28"
			(at -0.0127 -1.8034 0)
			(unlocked yes)
			(layer "B.Fab")
			(hide yes)
			(effects
				(font
					(size 1.016 1.016)
					(thickness 0.1524)
				)
				(justify mirror)
			)
		)
		(property "Device Type" "TPAD28"
			(at -0.0127 -3.3274 0)
			(unlocked yes)
			(layer "B.Fab")
			(hide yes)
			(effects
				(font
					(size 1.016 1.016)
					(thickness 0.1524)
				)
				(justify mirror)
			)
		)
		(duplicate_pad_numbers_are_jumpers no)
		(fp_poly
			(pts
				(arc
					(start 0.3556 0)
					(mid -0.3556 0)
					(end 0.3556 0)
				)
			)
			(stroke
				(width 0)
				(type default)
			)
			(fill no)
			(layer "B.CrtYd")
		)
		(fp_poly
			(pts
				(arc
					(start 0.6096 0)
					(mid -0.6096 0)
					(end 0.6096 0)
				)
			)
			(stroke
				(width 0)
				(type default)
			)
			(fill no)
			(layer "B.Fab")
		)
		(pad "1" smd circle
			(at 0 0 180)
			(size 0.7112 0.7112)
			(layers "B.Cu" "B.Mask" "B.Paste")
			(net "ICE1_TDI")
		)
	)
	(footprint ""
		(layer "B.Cu")
		(at 274.193 -170.561 90)
		(property "Reference" "R309"
			(at 0 0 90)
			(layer "B.SilkS")
			(hide yes)
			(effects
				(font
					(size 1.27 1.27)
				)
				(justify mirror)
			)
		)
		(property "Value" "10KR2F-2-GP"
			(at -0.064008 -3.993896 90)
			(unlocked yes)
			(layer "B.Fab")
			(hide yes)
			(effects
				(font
					(size 1.016 1.016)
					(thickness 0.1524)
				)
				(justify mirror)
			)
		)
		(property "Device Type" "R402H16"
			(at -0.064008 -5.517896 90)
			(unlocked yes)
			(layer "B.Fab")
			(hide yes)
			(effects
				(font
					(size 1.016 1.016)
					(thickness 0.1524)
				)
				(justify mirror)
			)
		)
		(duplicate_pad_numbers_are_jumpers no)
		(fp_line
			(start 0.508 -0.9398)
			(end 0.508 0.9398)
			(stroke
				(width 0.1524)
				(type default)
			)
			(layer "B.SilkS")
		)
		(fp_line
			(start -0.508 -0.9398)
			(end 0.508 -0.9398)
			(stroke
				(width 0.1524)
				(type default)
			)
			(layer "B.SilkS")
		)
		(fp_rect
			(start 0.508 0.9398)
			(end -0.508 -0.9398)
			(stroke
				(width 0)
				(type default)
			)
			(fill no)
			(layer "B.CrtYd")
		)
		(fp_rect
			(start 0.508 0.9398)
			(end -0.508 -0.9398)
			(stroke
				(width 0)
				(type default)
			)
			(fill no)
			(layer "B.Fab")
		)
		(pad "1" smd custom
			(at 0 -0.4445 270)
			(size 0.1397 0.1397)
			(layers "B.Cu" "B.Mask" "B.Paste")
			(net "P3V3_STBY")
			(options
				(clearance outline)
				(anchor circle)
			)
			(primitives
				(gr_poly
					(pts
						(arc
							(start -0.1778 0.2794)
							(mid -0.249642 0.249642)
							(end -0.2794 0.1778)
						)
						(arc
							(start -0.2794 -0.1778)
							(mid -0.249642 -0.249642)
							(end -0.1778 -0.2794)
						)
						(arc
							(start 0.1778 -0.2794)
							(mid 0.249642 -0.249642)
							(end 0.2794 -0.1778)
						)
						(arc
							(start 0.2794 0.1778)
							(mid 0.249642 0.249642)
							(end 0.1778 0.2794)
						)
					)
					(width 0)
					(fill yes)
				)
			)
		)
		(pad "2" smd custom
			(at 0 0.4445 270)
			(size 0.1397 0.1397)
			(layers "B.Cu" "B.Mask" "B.Paste")
			(net "BMC_10G_SCL_2")
			(options
				(clearance outline)
				(anchor circle)
			)
			(primitives
				(gr_poly
					(pts
						(arc
							(start -0.1778 0.2794)
							(mid -0.249642 0.249642)
							(end -0.2794 0.1778)
						)
						(arc
							(start -0.2794 -0.1778)
							(mid -0.249642 -0.249642)
							(end -0.1778 -0.2794)
						)
						(arc
							(start 0.1778 -0.2794)
							(mid 0.249642 -0.249642)
							(end 0.2794 -0.1778)
						)
						(arc
							(start 0.2794 0.1778)
							(mid 0.249642 0.249642)
							(end 0.1778 0.2794)
						)
					)
					(width 0)
					(fill yes)
				)
			)
		)
	)
	(footprint ""
		(layer "B.Cu")
		(at 108.020612 -210.439 -90)
		(property "Reference" "SR908"
			(at 0 0 90)
			(layer "B.SilkS")
			(hide yes)
			(effects
				(font
					(size 1.27 1.27)
				)
				(justify mirror)
			)
		)
		(property "Value" "4K7R2F-GP"
			(at -0.064008 -3.993896 270)
			(unlocked yes)
			(layer "B.Fab")
			(hide yes)
			(effects
				(font
					(size 1.016 1.016)
					(thickness 0.1524)
				)
				(justify mirror)
			)
		)
		(property "Device Type" "R402H16"
			(at -0.064008 -5.517896 270)
			(unlocked yes)
			(layer "B.Fab")
			(hide yes)
			(effects
				(font
					(size 1.016 1.016)
					(thickness 0.1524)
				)
				(justify mirror)
			)
		)
		(duplicate_pad_numbers_are_jumpers no)
		(fp_line
			(start -0.508 -0.9398)
			(end 0.508 -0.9398)
			(stroke
				(width 0.1524)
				(type default)
			)
			(layer "B.SilkS")
		)
		(fp_line
			(start 0.508 -0.9398)
			(end 0.508 0.9398)
			(stroke
				(width 0.1524)
				(type default)
			)
			(layer "B.SilkS")
		)
		(fp_rect
			(start 0.508 0.9398)
			(end -0.508 -0.9398)
			(stroke
				(width 0)
				(type default)
			)
			(fill no)
			(layer "B.CrtYd")
		)
		(fp_rect
			(start 0.508 0.9398)
			(end -0.508 -0.9398)
			(stroke
				(width 0)
				(type default)
			)
			(fill no)
			(layer "B.Fab")
		)
		(pad "1" smd custom
			(at 0 -0.4445 90)
			(size 0.1397 0.1397)
			(layers "B.Cu" "B.Mask" "B.Paste")
			(net "REDV_MODE")
			(options
				(clearance outline)
				(anchor circle)
			)
			(primitives
				(gr_poly
					(pts
						(arc
							(start -0.1778 0.2794)
							(mid -0.249642 0.249642)
							(end -0.2794 0.1778)
						)
						(arc
							(start -0.2794 -0.1778)
							(mid -0.249642 -0.249642)
							(end -0.1778 -0.2794)
						)
						(arc
							(start 0.1778 -0.2794)
							(mid 0.249642 -0.249642)
							(end 0.2794 -0.1778)
						)
						(arc
							(start 0.2794 0.1778)
							(mid 0.249642 0.249642)
							(end 0.1778 0.2794)
						)
					)
					(width 0)
					(fill yes)
				)
			)
		)
		(pad "2" smd custom
			(at 0 0.4445 90)
			(size 0.1397 0.1397)
			(layers "B.Cu" "B.Mask" "B.Paste")
			(net "GND")
			(options
				(clearance outline)
				(anchor circle)
			)
			(primitives
				(gr_poly
					(pts
						(arc
							(start -0.1778 0.2794)
							(mid -0.249642 0.249642)
							(end -0.2794 0.1778)
						)
						(arc
							(start -0.2794 -0.1778)
							(mid -0.249642 -0.249642)
							(end -0.1778 -0.2794)
						)
						(arc
							(start 0.1778 -0.2794)
							(mid 0.249642 -0.249642)
							(end 0.2794 -0.1778)
						)
						(arc
							(start 0.2794 0.1778)
							(mid 0.249642 0.249642)
							(end 0.1778 0.2794)
						)
					)
					(width 0)
					(fill yes)
				)
			)
		)
	)
	(footprint ""
		(layer "B.Cu")
		(at 322.961 -109.982 90)
		(property "Reference" "PR20"
			(at 0 0 90)
			(layer "B.SilkS")
			(hide yes)
			(effects
				(font
					(size 1.27 1.27)
				)
				(justify mirror)
			)
		)
		(property "Value" "3D01R5F-GP"
			(at 0 -8.9535 90)
			(unlocked yes)
			(layer "B.Fab")
			(hide yes)
			(effects
				(font
					(size 1.27 1.016)
					(thickness 0.1524)
				)
				(justify mirror)
			)
		)
		(property "Device Type" "R805H24"
			(at 0 -10.6299 90)
			(unlocked yes)
			(layer "B.Fab")
			(hide yes)
			(effects
				(font
					(size 1.27 1.016)
					(thickness 0.1524)
				)
				(justify mirror)
			)
		)
		(duplicate_pad_numbers_are_jumpers no)
		(fp_line
			(start 0.889 -1.7018)
			(end 0.889 0.2794)
			(stroke
				(width 0.1524)
				(type default)
			)
			(layer "B.SilkS")
		)
		(fp_line
			(start -0.889 -1.7018)
			(end 0.889 -1.7018)
			(stroke
				(width 0.1524)
				(type default)
			)
			(layer "B.SilkS")
		)
		(fp_line
			(start -0.889 -1.7018)
			(end -0.889 -0.381)
			(stroke
				(width 0.1524)
				(type default)
			)
			(layer "B.SilkS")
		)
		(fp_line
			(start 0.889 0.0762)
			(end 0.889 1.7018)
			(stroke
				(width 0.1524)
				(type default)
			)
			(layer "B.SilkS")
		)
		(fp_line
			(start 0.889 1.7018)
			(end -0.889 1.7018)
			(stroke
				(width 0.1524)
				(type default)
			)
			(layer "B.SilkS")
		)
		(fp_line
			(start -0.889 1.7018)
			(end -0.889 -0.508)
			(stroke
				(width 0.1524)
				(type default)
			)
			(layer "B.SilkS")
		)
		(fp_poly
			(pts
				(xy -0.9652 -1.778) (xy -0.9652 1.778) (xy 0.9652 1.778) (xy 0.9652 -1.778)
			)
			(stroke
				(width 0)
				(type default)
			)
			(fill no)
			(layer "B.CrtYd")
		)
		(fp_rect
			(start 0.9652 1.778)
			(end -0.9652 -1.778)
			(stroke
				(width 0)
				(type default)
			)
			(fill no)
			(layer "B.Fab")
		)
		(pad "1" smd rect
			(at 0 -0.9652 270)
			(size 1.397 1.143)
			(layers "B.Cu" "B.Mask" "B.Paste")
			(net "P3V3_STBY_VBST")
		)
		(pad "2" smd rect
			(at 0 0.9652 270)
			(size 1.397 1.143)
			(layers "B.Cu" "B.Mask" "B.Paste")
			(net "P3V3_STBY_VBST_RC")
		)
	)
	(footprint ""
		(layer "B.Cu")
		(at 95.26016 -37.719 180)
		(property "Reference" "SC944"
			(at 0 0 0)
			(layer "B.SilkS")
			(hide yes)
			(effects
				(font
					(size 1.27 1.27)
				)
				(justify mirror)
			)
		)
		(property "Value" "SCD1U6D3V1KX-GP"
			(at 2.8321 -1.7399 180)
			(unlocked yes)
			(layer "B.Fab")
			(hide yes)
			(effects
				(font
					(size 1.016 1.016)
					(thickness 0.1524)
				)
				(justify mirror)
			)
		)
		(property "Device Type" "C0201H13"
			(at 2.8321 -3.2639 180)
			(unlocked yes)
			(layer "B.Fab")
			(hide yes)
			(effects
				(font
					(size 1.016 1.016)
					(thickness 0.1524)
				)
				(justify mirror)
			)
		)
		(duplicate_pad_numbers_are_jumpers no)
		(fp_rect
			(start 0.2794 0.6477)
			(end -0.2794 -0.6477)
			(stroke
				(width 0)
				(type default)
			)
			(fill no)
			(layer "B.CrtYd")
		)
		(fp_rect
			(start 0.2794 0.6477)
			(end -0.2794 -0.6477)
			(stroke
				(width 0)
				(type default)
			)
			(fill no)
			(layer "B.Fab")
		)
		(pad "1" smd custom
			(at 0 -0.2794)
			(size 0.0762 0.0762)
			(layers "B.Cu" "B.Mask" "B.Paste")
			(net "P1V5_C")
			(options
				(clearance outline)
				(anchor circle)
			)
			(primitives
				(gr_poly
					(pts
						(arc
							(start 0.1524 0.127)
							(mid 0.137521 0.162921)
							(end 0.1016 0.1778)
						)
						(arc
							(start -0.1016 0.1778)
							(mid -0.137521 0.162921)
							(end -0.1524 0.127)
						)
						(arc
							(start -0.1524 -0.127)
							(mid -0.137521 -0.162921)
							(end -0.1016 -0.1778)
						)
						(arc
							(start 0.1016 -0.1778)
							(mid 0.137521 -0.162921)
							(end 0.1524 -0.127)
						)
					)
					(width 0)
					(fill yes)
				)
			)
		)
		(pad "2" smd custom
			(at 0 0.2794)
			(size 0.0762 0.0762)
			(layers "B.Cu" "B.Mask" "B.Paste")
			(net "GND")
			(options
				(clearance outline)
				(anchor circle)
			)
			(primitives
				(gr_poly
					(pts
						(arc
							(start 0.1524 0.127)
							(mid 0.137521 0.162921)
							(end 0.1016 0.1778)
						)
						(arc
							(start -0.1016 0.1778)
							(mid -0.137521 0.162921)
							(end -0.1524 0.127)
						)
						(arc
							(start -0.1524 -0.127)
							(mid -0.137521 -0.162921)
							(end -0.1016 -0.1778)
						)
						(arc
							(start 0.1016 -0.1778)
							(mid 0.137521 -0.162921)
							(end 0.1524 -0.127)
						)
					)
					(width 0)
					(fill yes)
				)
			)
		)
	)
	(footprint ""
		(layer "B.Cu")
		(at 114.848386 -31.84398)
		(property "Reference" "STP91"
			(at 0 0 0)
			(layer "B.SilkS")
			(hide yes)
			(effects
				(font
					(size 1.27 1.27)
				)
				(justify mirror)
			)
		)
		(property "Value" "TPAD28"
			(at -0.0127 -1.8034 0)
			(unlocked yes)
			(layer "B.Fab")
			(hide yes)
			(effects
				(font
					(size 1.016 1.016)
					(thickness 0.1524)
				)
				(justify mirror)
			)
		)
		(property "Device Type" "TPAD28"
			(at -0.0127 -3.3274 0)
			(unlocked yes)
			(layer "B.Fab")
			(hide yes)
			(effects
				(font
					(size 1.016 1.016)
					(thickness 0.1524)
				)
				(justify mirror)
			)
		)
		(duplicate_pad_numbers_are_jumpers no)
		(fp_poly
			(pts
				(arc
					(start 0.3556 0)
					(mid -0.3556 0)
					(end 0.3556 0)
				)
			)
			(stroke
				(width 0)
				(type default)
			)
			(fill no)
			(layer "B.CrtYd")
		)
		(fp_poly
			(pts
				(arc
					(start 0.6096 0)
					(mid -0.6096 0)
					(end 0.6096 0)
				)
			)
			(stroke
				(width 0)
				(type default)
			)
			(fill no)
			(layer "B.Fab")
		)
		(pad "1" smd circle
			(at 0 0 180)
			(size 0.7112 0.7112)
			(layers "B.Cu" "B.Mask" "B.Paste")
			(net "IOC_GPIO_12")
		)
	)
	(footprint ""
		(layer "B.Cu")
		(at 296.790872 -176.602136 -90)
		(property "Reference" "C214"
			(at 0 0 90)
			(layer "B.SilkS")
			(hide yes)
			(effects
				(font
					(size 1.27 1.27)
				)
				(justify mirror)
			)
		)
		(property "Value" "SC1U10V2KX-1GP"
			(at -1.1811 -2.7051 270)
			(unlocked yes)
			(layer "B.Fab")
			(hide yes)
			(effects
				(font
					(size 1.016 1.016)
					(thickness 0.1524)
				)
				(justify mirror)
			)
		)
		(property "Device Type" "C402H22"
			(at -1.1811 -4.2291 270)
			(unlocked yes)
			(layer "B.Fab")
			(hide yes)
			(effects
				(font
					(size 1.016 1.016)
					(thickness 0.1524)
				)
				(justify mirror)
			)
		)
		(duplicate_pad_numbers_are_jumpers no)
		(fp_rect
			(start 0.4318 0.9525)
			(end -0.4318 -0.9525)
			(stroke
				(width 0)
				(type default)
			)
			(fill no)
			(layer "B.CrtYd")
		)
		(fp_rect
			(start 0.4318 0.9525)
			(end -0.4318 -0.9525)
			(stroke
				(width 0)
				(type default)
			)
			(fill no)
			(layer "B.Fab")
		)
		(pad "1" smd custom
			(at 0 -0.4445 90)
			(size 0.1524 0.1524)
			(layers "B.Cu" "B.Mask" "B.Paste")
			(net "P3V3_STBY")
			(options
				(clearance outline)
				(anchor circle)
			)
			(primitives
				(gr_poly
					(pts
						(arc
							(start 0.3048 0.2032)
							(mid 0.275042 0.275042)
							(end 0.2032 0.3048)
						)
						(arc
							(start -0.2032 0.3048)
							(mid -0.275042 0.275042)
							(end -0.3048 0.2032)
						)
						(arc
							(start -0.3048 -0.2032)
							(mid -0.275042 -0.275042)
							(end -0.2032 -0.3048)
						)
						(arc
							(start 0.2032 -0.3048)
							(mid 0.275042 -0.275042)
							(end 0.3048 -0.2032)
						)
					)
					(width 0)
					(fill yes)
				)
			)
		)
		(pad "2" smd custom
			(at 0 0.4445 90)
			(size 0.1524 0.1524)
			(layers "B.Cu" "B.Mask" "B.Paste")
			(net "GND")
			(options
				(clearance outline)
				(anchor circle)
			)
			(primitives
				(gr_poly
					(pts
						(arc
							(start 0.3048 0.2032)
							(mid 0.275042 0.275042)
							(end 0.2032 0.3048)
						)
						(arc
							(start -0.2032 0.3048)
							(mid -0.275042 0.275042)
							(end -0.3048 0.2032)
						)
						(arc
							(start -0.3048 -0.2032)
							(mid -0.275042 -0.275042)
							(end -0.2032 -0.3048)
						)
						(arc
							(start 0.2032 -0.3048)
							(mid 0.275042 -0.275042)
							(end 0.3048 -0.2032)
						)
					)
					(width 0)
					(fill yes)
				)
			)
		)
	)
	(footprint ""
		(layer "B.Cu")
		(at 323.342 -182.372)
		(property "Reference" "C8083"
			(at 0 0 0)
			(layer "B.SilkS")
			(hide yes)
			(effects
				(font
					(size 1.27 1.27)
				)
				(justify mirror)
			)
		)
		(property "Value" "SCD1U25V2KX-2-GP"
			(at -1.1811 -2.7051 0)
			(unlocked yes)
			(layer "B.Fab")
			(hide yes)
			(effects
				(font
					(size 1.016 1.016)
					(thickness 0.1524)
				)
				(justify mirror)
			)
		)
		(property "Device Type" "C402H22"
			(at -1.1811 -4.2291 0)
			(unlocked yes)
			(layer "B.Fab")
			(hide yes)
			(effects
				(font
					(size 1.016 1.016)
					(thickness 0.1524)
				)
				(justify mirror)
			)
		)
		(duplicate_pad_numbers_are_jumpers no)
		(fp_rect
			(start 0.4318 0.9525)
			(end -0.4318 -0.9525)
			(stroke
				(width 0)
				(type default)
			)
			(fill no)
			(layer "B.CrtYd")
		)
		(fp_rect
			(start 0.4318 0.9525)
			(end -0.4318 -0.9525)
			(stroke
				(width 0)
				(type default)
			)
			(fill no)
			(layer "B.Fab")
		)
		(pad "1" smd custom
			(at 0 -0.4445 180)
			(size 0.1524 0.1524)
			(layers "B.Cu" "B.Mask" "B.Paste")
			(net "ADC_P0V955_C")
			(options
				(clearance outline)
				(anchor circle)
			)
			(primitives
				(gr_poly
					(pts
						(arc
							(start 0.3048 0.2032)
							(mid 0.275042 0.275042)
							(end 0.2032 0.3048)
						)
						(arc
							(start -0.2032 0.3048)
							(mid -0.275042 0.275042)
							(end -0.3048 0.2032)
						)
						(arc
							(start -0.3048 -0.2032)
							(mid -0.275042 -0.275042)
							(end -0.2032 -0.3048)
						)
						(arc
							(start 0.2032 -0.3048)
							(mid 0.275042 -0.275042)
							(end 0.3048 -0.2032)
						)
					)
					(width 0)
					(fill yes)
				)
			)
		)
		(pad "2" smd custom
			(at 0 0.4445 180)
			(size 0.1524 0.1524)
			(layers "B.Cu" "B.Mask" "B.Paste")
			(net "GND")
			(options
				(clearance outline)
				(anchor circle)
			)
			(primitives
				(gr_poly
					(pts
						(arc
							(start 0.3048 0.2032)
							(mid 0.275042 0.275042)
							(end 0.2032 0.3048)
						)
						(arc
							(start -0.2032 0.3048)
							(mid -0.275042 0.275042)
							(end -0.3048 0.2032)
						)
						(arc
							(start -0.3048 -0.2032)
							(mid -0.275042 -0.275042)
							(end -0.2032 -0.3048)
						)
						(arc
							(start 0.2032 -0.3048)
							(mid 0.275042 -0.275042)
							(end 0.3048 -0.2032)
						)
					)
					(width 0)
					(fill yes)
				)
			)
		)
	)
	(footprint ""
		(layer "B.Cu")
		(at 112.40897 -82.296)
		(property "Reference" "STP154"
			(at 0 0 0)
			(layer "B.SilkS")
			(hide yes)
			(effects
				(font
					(size 1.27 1.27)
				)
				(justify mirror)
			)
		)
		(property "Value" "TPAD28"
			(at -0.0127 -1.8034 0)
			(unlocked yes)
			(layer "B.Fab")
			(hide yes)
			(effects
				(font
					(size 1.016 1.016)
					(thickness 0.1524)
				)
				(justify mirror)
			)
		)
		(property "Device Type" "TPAD28"
			(at -0.0127 -3.3274 0)
			(unlocked yes)
			(layer "B.Fab")
			(hide yes)
			(effects
				(font
					(size 1.016 1.016)
					(thickness 0.1524)
				)
				(justify mirror)
			)
		)
		(duplicate_pad_numbers_are_jumpers no)
		(fp_poly
			(pts
				(arc
					(start 0.3556 0)
					(mid -0.3556 0)
					(end 0.3556 0)
				)
			)
			(stroke
				(width 0)
				(type default)
			)
			(fill no)
			(layer "B.CrtYd")
		)
		(fp_poly
			(pts
				(arc
					(start 0.6096 0)
					(mid -0.6096 0)
					(end 0.6096 0)
				)
			)
			(stroke
				(width 0)
				(type default)
			)
			(fill no)
			(layer "B.Fab")
		)
		(pad "1" smd circle
			(at 0 0 180)
			(size 0.7112 0.7112)
			(layers "B.Cu" "B.Mask" "B.Paste")
			(net "EXP_LED_13")
		)
	)
	(footprint ""
		(layer "B.Cu")
		(at 113.55197 -81.661)
		(property "Reference" "STP62"
			(at 0 0 0)
			(layer "B.SilkS")
			(hide yes)
			(effects
				(font
					(size 1.27 1.27)
				)
				(justify mirror)
			)
		)
		(property "Value" "TPAD28"
			(at -0.0127 -1.8034 0)
			(unlocked yes)
			(layer "B.Fab")
			(hide yes)
			(effects
				(font
					(size 1.016 1.016)
					(thickness 0.1524)
				)
				(justify mirror)
			)
		)
		(property "Device Type" "TPAD28"
			(at -0.0127 -3.3274 0)
			(unlocked yes)
			(layer "B.Fab")
			(hide yes)
			(effects
				(font
					(size 1.016 1.016)
					(thickness 0.1524)
				)
				(justify mirror)
			)
		)
		(duplicate_pad_numbers_are_jumpers no)
		(fp_poly
			(pts
				(arc
					(start 0.3556 0)
					(mid -0.3556 0)
					(end 0.3556 0)
				)
			)
			(stroke
				(width 0)
				(type default)
			)
			(fill no)
			(layer "B.CrtYd")
		)
		(fp_poly
			(pts
				(arc
					(start 0.6096 0)
					(mid -0.6096 0)
					(end 0.6096 0)
				)
			)
			(stroke
				(width 0)
				(type default)
			)
			(fill no)
			(layer "B.Fab")
		)
		(pad "1" smd circle
			(at 0 0 180)
			(size 0.7112 0.7112)
			(layers "B.Cu" "B.Mask" "B.Paste")
			(net "EXP_TEST_MUX24")
		)
	)
)
